(kicad_pcb
	(version 20260206)
	(generator "pcbnew")
	(generator_version "10.0")
	(general
		(thickness 1.6)
		(legacy_teardrops no)
	)
	(paper "A4")
	(title_block
		(title "baseboard — 13948-1b.1110WZS1818.brd")
		(comment 1 "Honey Badger (Wiwynn) / footprints 844-848 of 2523")
	)
	(layers
		(0 "F.Cu" signal "TOP")
		(4 "In1.Cu" signal "L2GND")
		(6 "In2.Cu" signal "L3")
		(8 "In3.Cu" signal "L4VCC")
		(10 "In4.Cu" signal "L5VCC")
		(12 "In5.Cu" signal "L6")
		(14 "In6.Cu" signal "L7GND")
		(2 "B.Cu" signal "BOTTOM")
		(9 "F.Adhes" user "F.Adhesive")
		(11 "B.Adhes" user "B.Adhesive")
		(13 "F.Paste" user "Package Geometry/Pastemask Top")
		(15 "B.Paste" user "Package Geometry/Pastemask Bottom")
		(5 "F.SilkS" user "Ref Des/Silkscreen Top")
		(7 "B.SilkS" user "Ref Des/Silkscreen Bottom")
		(1 "F.Mask" user "Board Geometry/Soldermask Top")
		(3 "B.Mask" user "Board Geometry/Soldermask Bottom")
		(17 "Dwgs.User" user "User.Drawings")
		(19 "Cmts.User" user "User.Comments")
		(21 "Eco1.User" user "User.Eco1")
		(23 "Eco2.User" user "User.Eco2")
		(25 "Edge.Cuts" user "Board Geometry/Outline")
		(27 "Margin" user)
		(31 "F.CrtYd" user "Package Geometry/Place Bound Top")
		(29 "B.CrtYd" user "Package Geometry/Place Bound Bottom")
		(35 "F.Fab" user "Ref Des/Assembly Top")
		(33 "B.Fab" user "Ref Des/Assembly Bottom")
	)
	(footprint ""
		(layer "F.Cu")
		(at 76.816966 -84.328 -90)
		(property "Reference" "SC1226"
			(at 0 0 270)
			(layer "F.SilkS")
			(hide yes)
			(effects
				(font
					(size 1.27 1.27)
				)
			)
		)
		(property "Value" "SCD1U6D3V1KX-GP"
			(at -2.8321 -1.7399 270)
			(unlocked yes)
			(layer "F.Fab")
			(hide yes)
			(effects
				(font
					(size 1.016 1.016)
					(thickness 0.1524)
				)
			)
		)
		(property "Device Type" "C0201H13"
			(at -2.8321 -3.2639 270)
			(unlocked yes)
			(layer "F.Fab")
			(hide yes)
			(effects
				(font
					(size 1.016 1.016)
					(thickness 0.1524)
				)
			)
		)
		(duplicate_pad_numbers_are_jumpers no)
		(fp_rect
			(start -0.2794 0.6477)
			(end 0.2794 -0.6477)
			(stroke
				(width 0)
				(type default)
			)
			(fill no)
			(layer "F.CrtYd")
		)
		(fp_rect
			(start -0.2794 0.6477)
			(end 0.2794 -0.6477)
			(stroke
				(width 0)
				(type default)
			)
			(fill no)
			(layer "F.Fab")
		)
		(pad "1" smd custom
			(at 0 -0.2794 270)
			(size 0.0762 0.0762)
			(layers "F.Cu" "F.Mask" "F.Paste")
			(net "P1V8_E")
			(options
				(clearance outline)
				(anchor circle)
			)
			(primitives
				(gr_poly
					(pts
						(arc
							(start 0.1524 -0.127)
							(mid 0.137521 -0.162921)
							(end 0.1016 -0.1778)
						)
						(arc
							(start -0.1016 -0.1778)
							(mid -0.137521 -0.162921)
							(end -0.1524 -0.127)
						)
						(arc
							(start -0.1524 0.127)
							(mid -0.137521 0.162921)
							(end -0.1016 0.1778)
						)
						(arc
							(start 0.1016 0.1778)
							(mid 0.137521 0.162921)
							(end 0.1524 0.127)
						)
					)
					(width 0)
					(fill yes)
				)
			)
		)
		(pad "2" smd custom
			(at 0 0.2794 270)
			(size 0.0762 0.0762)
			(layers "F.Cu" "F.Mask" "F.Paste")
			(net "GND")
			(options
				(clearance outline)
				(anchor circle)
			)
			(primitives
				(gr_poly
					(pts
						(arc
							(start 0.1524 -0.127)
							(mid 0.137521 -0.162921)
							(end 0.1016 -0.1778)
						)
						(arc
							(start -0.1016 -0.1778)
							(mid -0.137521 -0.162921)
							(end -0.1524 -0.127)
						)
						(arc
							(start -0.1524 0.127)
							(mid -0.137521 0.162921)
							(end -0.1016 0.1778)
						)
						(arc
							(start 0.1016 0.1778)
							(mid 0.137521 0.162921)
							(end 0.1524 0.127)
						)
					)
					(width 0)
					(fill yes)
				)
			)
		)
	)
	(footprint ""
		(layer "F.Cu")
		(at 223.393 -22.733)
		(property "Reference" "R7892"
			(at 0 0 0)
			(layer "F.SilkS")
			(hide yes)
			(effects
				(font
					(size 1.27 1.27)
				)
			)
		)
		(property "Value" "0R2J-2-GP"
			(at 0.064008 -3.993896 0)
			(unlocked yes)
			(layer "F.Fab")
			(hide yes)
			(effects
				(font
					(size 1.016 1.016)
					(thickness 0.1524)
				)
			)
		)
		(property "Device Type" "R402H16"
			(at 0.064008 -5.517896 0)
			(unlocked yes)
			(layer "F.Fab")
			(hide yes)
			(effects
				(font
					(size 1.016 1.016)
					(thickness 0.1524)
				)
			)
		)
		(duplicate_pad_numbers_are_jumpers no)
		(fp_line
			(start -0.508 -0.9398)
			(end -0.508 0.9398)
			(stroke
				(width 0.1524)
				(type default)
			)
			(layer "F.SilkS")
		)
		(fp_line
			(start 0.508 -0.9398)
			(end -0.508 -0.9398)
			(stroke
				(width 0.1524)
				(type default)
			)
			(layer "F.SilkS")
		)
		(fp_rect
			(start -0.508 0.9398)
			(end 0.508 -0.9398)
			(stroke
				(width 0)
				(type default)
			)
			(fill no)
			(layer "F.CrtYd")
		)
		(fp_rect
			(start -0.508 0.9398)
			(end 0.508 -0.9398)
			(stroke
				(width 0)
				(type default)
			)
			(fill no)
			(layer "F.Fab")
		)
		(pad "1" smd custom
			(at 0 -0.4445)
			(size 0.1397 0.1397)
			(layers "F.Cu" "F.Mask" "F.Paste")
			(net "LED_DR_LED1")
			(options
				(clearance outline)
				(anchor circle)
			)
			(primitives
				(gr_poly
					(pts
						(arc
							(start -0.1778 -0.2794)
							(mid -0.249642 -0.249642)
							(end -0.2794 -0.1778)
						)
						(arc
							(start -0.2794 0.1778)
							(mid -0.249642 0.249642)
							(end -0.1778 0.2794)
						)
						(arc
							(start 0.1778 0.2794)
							(mid 0.249642 0.249642)
							(end 0.2794 0.1778)
						)
						(arc
							(start 0.2794 -0.1778)
							(mid 0.249642 -0.249642)
							(end 0.1778 -0.2794)
						)
					)
					(width 0)
					(fill yes)
				)
			)
		)
		(pad "2" smd custom
			(at 0 0.4445)
			(size 0.1397 0.1397)
			(layers "F.Cu" "F.Mask" "F.Paste")
			(net "LED_PWR_N_ON")
			(options
				(clearance outline)
				(anchor circle)
			)
			(primitives
				(gr_poly
					(pts
						(arc
							(start -0.1778 -0.2794)
							(mid -0.249642 -0.249642)
							(end -0.2794 -0.1778)
						)
						(arc
							(start -0.2794 0.1778)
							(mid -0.249642 0.249642)
							(end -0.1778 0.2794)
						)
						(arc
							(start 0.1778 0.2794)
							(mid 0.249642 0.249642)
							(end 0.2794 0.1778)
						)
						(arc
							(start 0.2794 -0.1778)
							(mid 0.249642 -0.249642)
							(end 0.1778 -0.2794)
						)
					)
					(width 0)
					(fill yes)
				)
			)
		)
	)
	(footprint ""
		(layer "F.Cu")
		(at 160.02 -149.479 -90)
		(property "Reference" "SR725"
			(at 0 0 270)
			(layer "F.SilkS")
			(hide yes)
			(effects
				(font
					(size 1.27 1.27)
				)
			)
		)
		(property "Value" "4K7R2F-GP"
			(at 0.064008 -3.993896 270)
			(unlocked yes)
			(layer "F.Fab")
			(hide yes)
			(effects
				(font
					(size 1.016 1.016)
					(thickness 0.1524)
				)
			)
		)
		(property "Device Type" "R402H16"
			(at 0.064008 -5.517896 270)
			(unlocked yes)
			(layer "F.Fab")
			(hide yes)
			(effects
				(font
					(size 1.016 1.016)
					(thickness 0.1524)
				)
			)
		)
		(duplicate_pad_numbers_are_jumpers no)
		(fp_line
			(start -0.508 -0.9398)
			(end -0.508 0.9398)
			(stroke
				(width 0.1524)
				(type default)
			)
			(layer "F.SilkS")
		)
		(fp_line
			(start 0.508 -0.9398)
			(end -0.508 -0.9398)
			(stroke
				(width 0.1524)
				(type default)
			)
			(layer "F.SilkS")
		)
		(fp_rect
			(start -0.508 0.9398)
			(end 0.508 -0.9398)
			(stroke
				(width 0)
				(type default)
			)
			(fill no)
			(layer "F.CrtYd")
		)
		(fp_rect
			(start -0.508 0.9398)
			(end 0.508 -0.9398)
			(stroke
				(width 0)
				(type default)
			)
			(fill no)
			(layer "F.Fab")
		)
		(pad "1" smd custom
			(at 0 -0.4445 270)
			(size 0.1397 0.1397)
			(layers "F.Cu" "F.Mask" "F.Paste")
			(net "IOC_P3V3_SDA_14")
			(options
				(clearance outline)
				(anchor circle)
			)
			(primitives
				(gr_poly
					(pts
						(arc
							(start -0.1778 -0.2794)
							(mid -0.249642 -0.249642)
							(end -0.2794 -0.1778)
						)
						(arc
							(start -0.2794 0.1778)
							(mid -0.249642 0.249642)
							(end -0.1778 0.2794)
						)
						(arc
							(start 0.1778 0.2794)
							(mid 0.249642 0.249642)
							(end 0.2794 0.1778)
						)
						(arc
							(start 0.2794 -0.1778)
							(mid 0.249642 -0.249642)
							(end 0.1778 -0.2794)
						)
					)
					(width 0)
					(fill yes)
				)
			)
		)
		(pad "2" smd custom
			(at 0 0.4445 270)
			(size 0.1397 0.1397)
			(layers "F.Cu" "F.Mask" "F.Paste")
			(net "P3V3")
			(options
				(clearance outline)
				(anchor circle)
			)
			(primitives
				(gr_poly
					(pts
						(arc
							(start -0.1778 -0.2794)
							(mid -0.249642 -0.249642)
							(end -0.2794 -0.1778)
						)
						(arc
							(start -0.2794 0.1778)
							(mid -0.249642 0.249642)
							(end -0.1778 0.2794)
						)
						(arc
							(start 0.1778 0.2794)
							(mid 0.249642 0.249642)
							(end 0.2794 0.1778)
						)
						(arc
							(start 0.2794 -0.1778)
							(mid 0.249642 -0.249642)
							(end 0.1778 -0.2794)
						)
					)
					(width 0)
					(fill yes)
				)
			)
		)
	)
	(footprint ""
		(layer "F.Cu")
		(at 215.080596 -102.000812 180)
		(property "Reference" "PU10"
			(at 0 0 180)
			(layer "F.SilkS")
			(hide yes)
			(effects
				(font
					(size 1.27 1.27)
				)
			)
		)
		(property "Value" "TPS74801RGW-GP"
			(at -4.7244 -6.223 180)
			(unlocked yes)
			(layer "F.Fab")
			(hide yes)
			(effects
				(font
					(size 1.016 1.016)
					(thickness 0.1524)
				)
			)
		)
		(property "Device Type" "QFN20-1G3D15H40"
			(at -4.7244 -7.747 180)
			(unlocked yes)
			(layer "F.Fab")
			(hide yes)
			(effects
				(font
					(size 1.016 1.016)
					(thickness 0.1524)
				)
			)
		)
		(duplicate_pad_numbers_are_jumpers no)
		(fp_line
			(start 3.5179 3.5179)
			(end 3.5179 2.2479)
			(stroke
				(width 0.1524)
				(type default)
			)
			(layer "F.SilkS")
		)
		(fp_line
			(start 3.160522 -1.299972)
			(end 3.922522 -1.299972)
			(stroke
				(width 0.1524)
				(type default)
			)
			(layer "F.SilkS")
		)
		(fp_line
			(start 2.2479 3.5179)
			(end 3.5179 3.5179)
			(stroke
				(width 0.1524)
				(type default)
			)
			(layer "F.SilkS")
		)
		(fp_line
			(start 1.299972 3.160522)
			(end 1.299972 3.668522)
			(stroke
				(width 0.1524)
				(type default)
			)
			(layer "F.SilkS")
		)
		(fp_line
			(start -1.299972 -3.160522)
			(end -1.299972 -3.668522)
			(stroke
				(width 0.1524)
				(type default)
			)
			(layer "F.SilkS")
		)
		(fp_line
			(start -2.2479 -3.5179)
			(end -3.5179 -3.5179)
			(stroke
				(width 0.1524)
				(type default)
			)
			(layer "F.SilkS")
		)
		(fp_line
			(start -3.160522 1.299972)
			(end -3.922522 1.299972)
			(stroke
				(width 0.1524)
				(type default)
			)
			(layer "F.SilkS")
		)
		(fp_line
			(start -3.5179 3.5179)
			(end -2.2479 3.5179)
			(stroke
				(width 0.1524)
				(type default)
			)
			(layer "F.SilkS")
		)
		(fp_line
			(start -3.5179 2.2479)
			(end -3.5179 3.5179)
			(stroke
				(width 0.1524)
				(type default)
			)
			(layer "F.SilkS")
		)
		(fp_line
			(start -3.5179 -3.5179)
			(end -3.5179 -2.2479)
			(stroke
				(width 0.1524)
				(type default)
			)
			(layer "F.SilkS")
		)
		(fp_poly
			(pts
				(xy 3.5179 -3.5179) (xy 2.2479 -3.5179) (xy 3.5179 -2.2479)
			)
			(stroke
				(width 0)
				(type default)
			)
			(fill yes)
			(layer "F.SilkS")
		)
		(fp_rect
			(start -2.5019 2.5019)
			(end 2.5019 -2.5019)
			(stroke
				(width 0)
				(type default)
			)
			(fill no)
			(layer "F.CrtYd")
		)
		(fp_poly
			(pts
				(xy -3.5179 3.5179) (xy -3.5179 -3.5179) (xy 3.5179 -3.5179) (xy 3.5179 -2.5019) (xy -2.5019 -2.5019)
				(xy -2.5019 2.5019) (xy 2.5019 2.5019) (xy 2.5019 -2.49682) (xy 3.5179 -2.49682) (xy 3.5179 3.5179)
			)
			(stroke
				(width 0)
				(type default)
			)
			(fill no)
			(layer "F.CrtYd")
		)
		(fp_rect
			(start -3.5179 3.5179)
			(end 3.5179 -3.5179)
			(stroke
				(width 0)
				(type default)
			)
			(fill no)
			(layer "F.Fab")
		)
		(pad "1" smd rect
			(at 1.299972 -2.474722 180)
			(size 0.3556 1.0668)
			(layers "F.Cu" "F.Mask" "F.Paste")
			(net "P1V5_C")
		)
		(pad "2" smd rect
			(at 0.649986 -2.474722 180)
			(size 0.3556 1.0668)
			(layers "F.Cu" "F.Mask" "F.Paste")
			(net "GND")
		)
		(pad "3" smd rect
			(at 0 -2.474722 180)
			(size 0.3556 1.0668)
			(layers "F.Cu" "F.Mask" "F.Paste")
			(net "GND")
		)
		(pad "4" smd rect
			(at -0.649986 -2.474722 180)
			(size 0.3556 1.0668)
			(layers "F.Cu" "F.Mask" "F.Paste")
			(net "GND")
		)
		(pad "5" smd rect
			(at -1.299972 -2.474722 180)
			(size 0.3556 1.0668)
			(layers "F.Cu" "F.Mask" "F.Paste")
			(net "TPS74801_P1V5_C_IN")
		)
		(pad "6" smd rect
			(at -2.474722 -1.299972 180)
			(size 1.0668 0.3556)
			(layers "F.Cu" "F.Mask" "F.Paste")
			(net "TPS74801_P1V5_C_IN")
		)
		(pad "7" smd rect
			(at -2.474722 -0.649986 180)
			(size 1.0668 0.3556)
			(layers "F.Cu" "F.Mask" "F.Paste")
			(net "TPS74801_P1V5_C_IN")
		)
		(pad "8" smd rect
			(at -2.474722 0 180)
			(size 1.0668 0.3556)
			(layers "F.Cu" "F.Mask" "F.Paste")
			(net "TPS74801_P1V5_C_IN")
		)
		(pad "9" smd rect
			(at -2.474722 0.649986 180)
			(size 1.0668 0.3556)
			(layers "F.Cu" "F.Mask" "F.Paste")
			(net "PWRGD_P1V5_C_PG")
		)
		(pad "10" smd rect
			(at -2.474722 1.299972 180)
			(size 1.0668 0.3556)
			(layers "F.Cu" "F.Mask" "F.Paste")
			(net "TPS74801_1V5_C_BIAS")
		)
		(pad "11" smd rect
			(at -1.299972 2.474722 180)
			(size 0.3556 1.0668)
			(layers "F.Cu" "F.Mask" "F.Paste")
			(net "TPS74801_1V5_C_EN")
		)
		(pad "12" smd rect
			(at -0.649986 2.474722 180)
			(size 0.3556 1.0668)
			(layers "F.Cu" "F.Mask" "F.Paste")
			(net "GND")
		)
		(pad "13" smd rect
			(at 0 2.474722 180)
			(size 0.3556 1.0668)
			(layers "F.Cu" "F.Mask" "F.Paste")
			(net "GND")
		)
		(pad "14" smd rect
			(at 0.649986 2.474722 180)
			(size 0.3556 1.0668)
			(layers "F.Cu" "F.Mask" "F.Paste")
			(net "GND")
		)
		(pad "15" smd rect
			(at 1.299972 2.474722 180)
			(size 0.3556 1.0668)
			(layers "F.Cu" "F.Mask" "F.Paste")
			(net "TPS74801_1V5_C_SS")
		)
		(pad "16" smd rect
			(at 2.474722 1.299972 180)
			(size 1.0668 0.3556)
			(layers "F.Cu" "F.Mask" "F.Paste")
			(net "TPS74801_1V5_C_FB")
		)
		(pad "17" smd rect
			(at 2.474722 0.649986 180)
			(size 1.0668 0.3556)
			(layers "F.Cu" "F.Mask" "F.Paste")
			(net "GND")
		)
		(pad "18" smd rect
			(at 2.474722 0 180)
			(size 1.0668 0.3556)
			(layers "F.Cu" "F.Mask" "F.Paste")
			(net "P1V5_C")
		)
		(pad "19" smd rect
			(at 2.474722 -0.649986 180)
			(size 1.0668 0.3556)
			(layers "F.Cu" "F.Mask" "F.Paste")
			(net "P1V5_C")
		)
		(pad "20" smd rect
			(at 2.474722 -1.299972 180)
			(size 1.0668 0.3556)
			(layers "F.Cu" "F.Mask" "F.Paste")
			(net "P1V5_C")
		)
		(pad "21" smd rect
			(at 0 0 180)
			(size 3.2512 3.2512)
			(layers "F.Cu" "F.Mask" "F.Paste")
			(net "GND")
		)
	)
	(footprint ""
		(layer "F.Cu")
		(at 308.991 -185.674 -90)
		(property "Reference" "SR849"
			(at 0 0 270)
			(layer "F.SilkS")
			(hide yes)
			(effects
				(font
					(size 1.27 1.27)
				)
			)
		)
		(property "Value" "4K75R2F-1-GP"
			(at 0.064008 -3.993896 270)
			(unlocked yes)
			(layer "F.Fab")
			(hide yes)
			(effects
				(font
					(size 1.016 1.016)
					(thickness 0.1524)
				)
			)
		)
		(property "Device Type" "R402H16"
			(at 0.064008 -5.517896 270)
			(unlocked yes)
			(layer "F.Fab")
			(hide yes)
			(effects
				(font
					(size 1.016 1.016)
					(thickness 0.1524)
				)
			)
		)
		(duplicate_pad_numbers_are_jumpers no)
		(fp_line
			(start -0.508 -0.9398)
			(end -0.508 0.9398)
			(stroke
				(width 0.1524)
				(type default)
			)
			(layer "F.SilkS")
		)
		(fp_line
			(start 0.508 -0.9398)
			(end -0.508 -0.9398)
			(stroke
				(width 0.1524)
				(type default)
			)
			(layer "F.SilkS")
		)
		(fp_rect
			(start -0.508 0.9398)
			(end 0.508 -0.9398)
			(stroke
				(width 0)
				(type default)
			)
			(fill no)
			(layer "F.CrtYd")
		)
		(fp_rect
			(start -0.508 0.9398)
			(end 0.508 -0.9398)
			(stroke
				(width 0)
				(type default)
			)
			(fill no)
			(layer "F.Fab")
		)
		(pad "1" smd custom
			(at 0 -0.4445 270)
			(size 0.1397 0.1397)
			(layers "F.Cu" "F.Mask" "F.Paste")
			(net "BMC_FW_DET_BOARD_VER_1")
			(options
				(clearance outline)
				(anchor circle)
			)
			(primitives
				(gr_poly
					(pts
						(arc
							(start -0.1778 -0.2794)
							(mid -0.249642 -0.249642)
							(end -0.2794 -0.1778)
						)
						(arc
							(start -0.2794 0.1778)
							(mid -0.249642 0.249642)
							(end -0.1778 0.2794)
						)
						(arc
							(start 0.1778 0.2794)
							(mid 0.249642 0.249642)
							(end 0.2794 0.1778)
						)
						(arc
							(start 0.2794 -0.1778)
							(mid 0.249642 -0.249642)
							(end 0.1778 -0.2794)
						)
					)
					(width 0)
					(fill yes)
				)
			)
		)
		(pad "2" smd custom
			(at 0 0.4445 270)
			(size 0.1397 0.1397)
			(layers "F.Cu" "F.Mask" "F.Paste")
			(net "GND")
			(options
				(clearance outline)
				(anchor circle)
			)
			(primitives
				(gr_poly
					(pts
						(arc
							(start -0.1778 -0.2794)
							(mid -0.249642 -0.249642)
							(end -0.2794 -0.1778)
						)
						(arc
							(start -0.2794 0.1778)
							(mid -0.249642 0.249642)
							(end -0.1778 0.2794)
						)
						(arc
							(start 0.1778 0.2794)
							(mid 0.249642 0.249642)
							(end 0.2794 0.1778)
						)
						(arc
							(start 0.2794 -0.1778)
							(mid 0.249642 -0.249642)
							(end 0.1778 -0.2794)
						)
					)
					(width 0)
					(fill yes)
				)
			)
		)
	)
)
